# T6G (Grand Teton) — schematic netlist excerpt (pin names and nets, part order shuffled) for the footprints in the layout excerpt that follows; sources: Cadence DE-HDL packaged netlist, KiCad conversion of 04192023_DAF0TMB3IC0_F0TG_MB_C_brd_V02_OCP.brd

PC509_1  Q_CAP  0.1UF 25V 10% X7R  pkg 0402  page 225 : A = SW_P12V_AUX_PVDD11_S3_P1_FLT ; B = GND

U200  LTC4307CMS8  IC  pkg MSOP8  page 248
  ENABLE  = SMB_BMC_GPU_EN_R3
  SCL_OUT  = SMB_2_BMC_GPU_BUF_R_SCL
  SCL_IN  = SMB_2_BMC_GPU_R_SCL
  GND  = GND
  READY  = NC
  SDA_IN  = SMB_2_BMC_GPU_R_SDA
  SDA_OUT  = SMB_2_BMC_GPU_BUF_R_SDA
  VCC  = P3V3_AUX

(kicad_pcb
	(version 20260206)
	(generator "pcbnew")
	(generator_version "10.0")
	(general
		(thickness 1.6)
		(legacy_teardrops no)
	)
	(paper "A4")
	(title_block
		(title "04192023_DAF0TMB3IC0_F0TG_MB_C_brd_V02_OCP.brd")
		(comment 1 "Grand Teton / footprints 1961-1962 of 8354")
	)
	(layers
		(0 "F.Cu" signal "TOP")
		(4 "In1.Cu" signal "GND")
		(6 "In2.Cu" signal "IN1")
		(8 "In3.Cu" signal "GND1")
		(10 "In4.Cu" signal "IN2")
		(12 "In5.Cu" signal "GND2")
		(14 "In6.Cu" signal "IN3")
		(16 "In7.Cu" signal "GND3")
		(18 "In8.Cu" signal "VCC")
		(20 "In9.Cu" signal "VCC1")
		(22 "In10.Cu" signal "GND4")
		(24 "In11.Cu" signal "IN4")
		(26 "In12.Cu" signal "GND5")
		(28 "In13.Cu" signal "IN5")
		(30 "In14.Cu" signal "GND6")
		(32 "In15.Cu" signal "IN6")
		(34 "In16.Cu" signal "GND7")
		(2 "B.Cu" signal "BOTTOM")
		(9 "F.Adhes" user "F.Adhesive")
		(11 "B.Adhes" user "B.Adhesive")
		(13 "F.Paste" user "Package Geometry/Pastemask Top")
		(15 "B.Paste" user "Package Geometry/Pastemask Bottom")
		(5 "F.SilkS" user "Ref Des/Silkscreen Top")
		(7 "B.SilkS" user "Ref Des/Silkscreen Bottom")
		(1 "F.Mask" user "Board Geometry/Soldermask Top")
		(3 "B.Mask" user "Board Geometry/Soldermask Bottom")
		(17 "Dwgs.User" user "User.Drawings")
		(19 "Cmts.User" user "User.Comments")
		(21 "Eco1.User" user "User.Eco1")
		(23 "Eco2.User" user "User.Eco2")
		(25 "Edge.Cuts" user "Board Geometry/Outline")
		(27 "Margin" user)
		(31 "F.CrtYd" user "Package Geometry/Place Bound Top")
		(29 "B.CrtYd" user "Package Geometry/Place Bound Bottom")
		(35 "F.Fab" user "Ref Des/Assembly Top")
		(33 "B.Fab" user "Ref Des/Assembly Bottom")
	)
	(footprint ""
		(layer "F.Cu")
		(at 187.11037 -355.705156)
		(property "Reference" "PC509_1"
			(at 0 0 0)
			(layer "F.SilkS")
			(hide yes)
			(effects
				(font
					(size 1.27 1.27)
				)
			)
		)
		(property "Value" ""
			(at 0 0 0)
			(layer "F.Fab")
			(effects
				(font
					(size 1.27 1.27)
				)
			)
		)
		(duplicate_pad_numbers_are_jumpers no)
		(fp_line
			(start -0.7874 -0.4064)
			(end 0.7874 -0.4064)
			(stroke
				(width 0.1524)
				(type default)
			)
			(layer "F.SilkS")
		)
		(fp_line
			(start -0.7874 0.4064)
			(end -0.7874 -0.4064)
			(stroke
				(width 0.1524)
				(type default)
			)
			(layer "F.SilkS")
		)
		(fp_line
			(start 0.7874 -0.4064)
			(end 0.7874 0.4064)
			(stroke
				(width 0.1524)
				(type default)
			)
			(layer "F.SilkS")
		)
		(fp_line
			(start 0.7874 0.4064)
			(end -0.7874 0.4064)
			(stroke
				(width 0.1524)
				(type default)
			)
			(layer "F.SilkS")
		)
		(fp_line
			(start -0.67945 -0.305054)
			(end -0.12065 -0.305054)
			(stroke
				(width 0.1)
				(type default)
			)
			(layer "F.Fab")
		)
		(fp_line
			(start -0.67945 0.3048)
			(end -0.67945 -0.305054)
			(stroke
				(width 0.1)
				(type default)
			)
			(layer "F.Fab")
		)
		(fp_line
			(start -0.12065 -0.305054)
			(end -0.12065 -0.2794)
			(stroke
				(width 0.1)
				(type default)
			)
			(layer "F.Fab")
		)
		(fp_line
			(start -0.12065 -0.2794)
			(end 0.12065 -0.2794)
			(stroke
				(width 0.1)
				(type default)
			)
			(layer "F.Fab")
		)
		(fp_line
			(start -0.12065 0.2794)
			(end -0.12065 0.3048)
			(stroke
				(width 0.1)
				(type default)
			)
			(layer "F.Fab")
		)
		(fp_line
			(start -0.12065 0.3048)
			(end -0.67945 0.3048)
			(stroke
				(width 0.1)
				(type default)
			)
			(layer "F.Fab")
		)
		(fp_line
			(start 0.120396 0.2794)
			(end -0.12065 0.2794)
			(stroke
				(width 0.1)
				(type default)
			)
			(layer "F.Fab")
		)
		(fp_line
			(start 0.120396 0.3048)
			(end 0.120396 0.2794)
			(stroke
				(width 0.1)
				(type default)
			)
			(layer "F.Fab")
		)
		(fp_line
			(start 0.12065 -0.3048)
			(end 0.67945 -0.3048)
			(stroke
				(width 0.1)
				(type default)
			)
			(layer "F.Fab")
		)
		(fp_line
			(start 0.12065 -0.2794)
			(end 0.12065 -0.3048)
			(stroke
				(width 0.1)
				(type default)
			)
			(layer "F.Fab")
		)
		(fp_line
			(start 0.67945 -0.3048)
			(end 0.67945 0.3048)
			(stroke
				(width 0.1)
				(type default)
			)
			(layer "F.Fab")
		)
		(fp_line
			(start 0.67945 0.3048)
			(end 0.120396 0.3048)
			(stroke
				(width 0.1)
				(type default)
			)
			(layer "F.Fab")
		)
		(pad "1" smd circle
			(at -0.40005 0)
			(size 0 0)
			(layers "F.Cu" "F.Mask" "F.Paste")
			(net "SW_P12V_AUX_PVDD11_S3_P1_FLT")
		)
		(pad "2" smd circle
			(at 0.40005 0)
			(size 0 0)
			(layers "F.Cu" "F.Mask" "F.Paste")
			(net "GND")
		)
	)
	(footprint ""
		(layer "F.Cu")
		(at 28.288488 -437.458358 180)
		(property "Reference" "U200"
			(at 3.169412 2.695194 0)
			(unlocked yes)
			(layer "F.SilkS")
			(effects
				(font
					(size 0.7874 0.5842)
					(thickness 0.1524)
				)
				(justify left)
			)
		)
		(property "Value" ""
			(at 0 0 180)
			(layer "F.Fab")
			(effects
				(font
					(size 1.27 1.27)
				)
			)
		)
		(duplicate_pad_numbers_are_jumpers no)
		(fp_line
			(start 1.3716 1.524)
			(end -1.3716 1.524)
			(stroke
				(width 0.1524)
				(type default)
			)
			(layer "F.SilkS")
		)
		(fp_line
			(start 1.3716 -1.524)
			(end 1.3716 1.524)
			(stroke
				(width 0.1524)
				(type default)
			)
			(layer "F.SilkS")
		)
		(fp_line
			(start 0.508 -1.524)
			(end 1.3716 -1.524)
			(stroke
				(width 0.1524)
				(type default)
			)
			(layer "F.SilkS")
		)
		(fp_line
			(start 0 -1.016)
			(end 0.508 -1.524)
			(stroke
				(width 0.1524)
				(type default)
			)
			(layer "F.SilkS")
		)
		(fp_line
			(start -0.508 -1.524)
			(end 0 -1.016)
			(stroke
				(width 0.1524)
				(type default)
			)
			(layer "F.SilkS")
		)
		(fp_line
			(start -1.3716 1.524)
			(end -1.3716 -1.524)
			(stroke
				(width 0.1524)
				(type default)
			)
			(layer "F.SilkS")
		)
		(fp_line
			(start -1.3716 -1.524)
			(end -0.508 -1.524)
			(stroke
				(width 0.1524)
				(type default)
			)
			(layer "F.SilkS")
		)
		(fp_poly
			(pts
				(xy -4.108704 -0.70358) (xy -4.108704 -1.32842) (xy -3.554984 -1.000252)
			)
			(stroke
				(width 0)
				(type default)
			)
			(fill yes)
			(layer "F.SilkS")
		)
		(fp_line
			(start 2.54 1.0668)
			(end 1.5494 1.0668)
			(stroke
				(width 0.1)
				(type default)
			)
			(layer "F.Fab")
		)
		(fp_line
			(start 2.54 -1.0668)
			(end 2.54 1.0668)
			(stroke
				(width 0.1)
				(type default)
			)
			(layer "F.Fab")
		)
		(fp_line
			(start 1.5494 1.524)
			(end -1.5494 1.524)
			(stroke
				(width 0.1)
				(type default)
			)
			(layer "F.Fab")
		)
		(fp_line
			(start 1.5494 1.0668)
			(end 1.5494 1.524)
			(stroke
				(width 0.1)
				(type default)
			)
			(layer "F.Fab")
		)
		(fp_line
			(start 1.5494 -1.0668)
			(end 2.54 -1.0668)
			(stroke
				(width 0.1)
				(type default)
			)
			(layer "F.Fab")
		)
		(fp_line
			(start 1.5494 -1.0668)
			(end 1.5494 1.0668)
			(stroke
				(width 0.1)
				(type default)
			)
			(layer "F.Fab")
		)
		(fp_line
			(start 1.5494 -1.524)
			(end 1.5494 -1.0668)
			(stroke
				(width 0.1)
				(type default)
			)
			(layer "F.Fab")
		)
		(fp_line
			(start -1.5494 1.524)
			(end -1.5494 1.0668)
			(stroke
				(width 0.1)
				(type default)
			)
			(layer "F.Fab")
		)
		(fp_line
			(start -1.5494 1.0668)
			(end -1.5494 -1.0668)
			(stroke
				(width 0.1)
				(type default)
			)
			(layer "F.Fab")
		)
		(fp_line
			(start -1.5494 1.0668)
			(end -2.54 1.0668)
			(stroke
				(width 0.1)
				(type default)
			)
			(layer "F.Fab")
		)
		(fp_line
			(start -1.5494 -1.0668)
			(end -1.5494 -1.524)
			(stroke
				(width 0.1)
				(type default)
			)
			(layer "F.Fab")
		)
		(fp_line
			(start -1.5494 -1.524)
			(end 1.5494 -1.524)
			(stroke
				(width 0.1)
				(type default)
			)
			(layer "F.Fab")
		)
		(fp_line
			(start -2.54 1.0668)
			(end -2.54 -1.0668)
			(stroke
				(width 0.1)
				(type default)
			)
			(layer "F.Fab")
		)
		(fp_line
			(start -2.54 -1.0668)
			(end -1.5494 -1.0668)
			(stroke
				(width 0.1)
				(type default)
			)
			(layer "F.Fab")
		)
		(fp_poly
			(pts
				(xy -3.60172 -0.719328) (xy -3.60172 -1.344168) (xy -3.048 -1.016)
			)
			(stroke
				(width 0)
				(type default)
			)
			(fill yes)
			(layer "F.Fab")
		)
		(pad "1" smd rect
			(at -2.232406 -0.975106 90)
			(size 0.3556 1.4224)
			(layers "F.Cu" "F.Mask" "F.Paste")
			(net "SMB_BMC_GPU_EN_R3")
		)
		(pad "2" smd rect
			(at -2.232406 -0.32512 90)
			(size 0.3556 1.4224)
			(layers "F.Cu" "F.Mask" "F.Paste")
			(net "SMB_2_BMC_GPU_BUF_R_SCL")
		)
		(pad "3" smd rect
			(at -2.232406 0.32512 90)
			(size 0.3556 1.4224)
			(layers "F.Cu" "F.Mask" "F.Paste")
			(net "SMB_2_BMC_GPU_R_SCL")
		)
		(pad "4" smd rect
			(at -2.232406 0.975106 90)
			(size 0.3556 1.4224)
			(layers "F.Cu" "F.Mask" "F.Paste")
			(net "GND")
		)
		(pad "5" smd rect
			(at 2.232406 0.975106 90)
			(size 0.3556 1.4224)
			(layers "F.Cu" "F.Mask" "F.Paste")
			(net "Net_10759")
		)
		(pad "6" smd rect
			(at 2.232406 0.32512 90)
			(size 0.3556 1.4224)
			(layers "F.Cu" "F.Mask" "F.Paste")
			(net "SMB_2_BMC_GPU_R_SDA")
		)
		(pad "7" smd rect
			(at 2.232406 -0.32512 90)
			(size 0.3556 1.4224)
			(layers "F.Cu" "F.Mask" "F.Paste")
			(net "SMB_2_BMC_GPU_BUF_R_SDA")
		)
		(pad "8" smd rect
			(at 2.232406 -0.975106 90)
			(size 0.3556 1.4224)
			(layers "F.Cu" "F.Mask" "F.Paste")
			(net "P3V3_AUX")
		)
	)
)
